<?xml version="1.0" encoding="UTF-8" standalone="no"?><root><o N="s9s_mb_2u" A="s9s_mb_2u"><a N="CDS_DI_CONTROL_MASK"><v V="0"/><o>2</o></a><g><v>4</v></g></o></root>